(kicad_pcb
	(version 20260206)
	(generator "pcbnew")
	(generator_version "10.0")
	(general
		(thickness 1.6)
		(legacy_teardrops no)
	)
	(paper "A4")
	(title_block
		(title "Wiwynn_Tioga_Pass_MB.brd")
		(comment 1 "Tioga Pass / footprints 445-448 of 4770")
	)
	(layers
		(0 "F.Cu" signal "TOP")
		(4 "In1.Cu" signal "L2GND")
		(6 "In2.Cu" signal "L3")
		(8 "In3.Cu" signal "L4GND")
		(10 "In4.Cu" signal "L5")
		(12 "In5.Cu" signal "L6GND")
		(14 "In6.Cu" signal "L7VCC")
		(16 "In7.Cu" signal "L8VCC")
		(18 "In8.Cu" signal "L9GND")
		(20 "In9.Cu" signal "L10")
		(22 "In10.Cu" signal "L11GND")
		(24 "In11.Cu" signal "L12")
		(26 "In12.Cu" signal "L13GND")
		(2 "B.Cu" signal "BOTTOM")
		(9 "F.Adhes" user "F.Adhesive")
		(11 "B.Adhes" user "B.Adhesive")
		(13 "F.Paste" user "Package Geometry/Pastemask Top")
		(15 "B.Paste" user "Package Geometry/Pastemask Bottom")
		(5 "F.SilkS" user "Ref Des/Silkscreen Top")
		(7 "B.SilkS" user "Ref Des/Silkscreen Bottom")
		(1 "F.Mask" user "Board Geometry/Soldermask Top")
		(3 "B.Mask" user "Board Geometry/Soldermask Bottom")
		(17 "Dwgs.User" user "User.Drawings")
		(19 "Cmts.User" user "User.Comments")
		(21 "Eco1.User" user "User.Eco1")
		(23 "Eco2.User" user "User.Eco2")
		(25 "Edge.Cuts" user "Board Geometry/Outline")
		(27 "Margin" user)
		(31 "F.CrtYd" user "Package Geometry/Place Bound Top")
		(29 "B.CrtYd" user "Package Geometry/Place Bound Bottom")
		(35 "F.Fab" user "Ref Des/Assembly Top")
		(33 "B.Fab" user "Ref Des/Assembly Bottom")
	)
	(footprint ""
		(layer "F.Cu")
		(at 362.523532 12.003278 -90)
		(property "Reference" "T1P23"
			(at 0 0 270)
			(layer "F.SilkS")
			(hide yes)
			(effects
				(font
					(size 1.27 1.27)
				)
			)
		)
		(property "Value" "*"
			(at -3.302 1.12395 270)
			(unlocked yes)
			(layer "F.Fab")
			(hide yes)
			(effects
				(font
					(size 0.889 0.889)
					(thickness 0.1524)
				)
			)
		)
		(property "Device Type" "TPAD-DIFF-4P-GP_DISCRET-GB3-TPA"
			(at -3.302 -0.40005 270)
			(unlocked yes)
			(layer "F.Fab")
			(hide yes)
			(effects
				(font
					(size 0.889 0.889)
					(thickness 0.1524)
				)
			)
		)
		(duplicate_pad_numbers_are_jumpers no)
		(fp_line
			(start -2.286 2.286)
			(end 2.286 2.286)
			(stroke
				(width 0.1524)
				(type default)
			)
			(layer "F.SilkS")
		)
		(fp_line
			(start 2.286 2.286)
			(end 2.286 -2.286)
			(stroke
				(width 0.1524)
				(type default)
			)
			(layer "F.SilkS")
		)
		(fp_line
			(start -2.286 -2.286)
			(end -2.286 2.286)
			(stroke
				(width 0.1524)
				(type default)
			)
			(layer "F.SilkS")
		)
		(fp_line
			(start 2.286 -2.286)
			(end -2.286 -2.286)
			(stroke
				(width 0.1524)
				(type default)
			)
			(layer "F.SilkS")
		)
		(fp_line
			(start -2.413 -2.413)
			(end -2.413 -1.143)
			(stroke
				(width 0.4064)
				(type default)
			)
			(layer "F.SilkS")
		)
		(fp_line
			(start -1.143 -2.413)
			(end -2.413 -2.413)
			(stroke
				(width 0.4064)
				(type default)
			)
			(layer "F.SilkS")
		)
		(fp_rect
			(start -2.54 2.54)
			(end 2.54 -2.54)
			(stroke
				(width 0)
				(type default)
			)
			(fill no)
			(layer "F.CrtYd")
		)
		(fp_rect
			(start -2.54 2.54)
			(end 2.54 -2.54)
			(stroke
				(width 0)
				(type default)
			)
			(fill no)
			(layer "F.Fab")
		)
		(pad "1" thru_hole circle
			(at -1.27 -1.27 270)
			(size 1.524 1.524)
			(drill 0.9144)
			(layers "*.Cu" "*.Mask")
			(remove_unused_layers no)
			(net "L12_100OHM_6INCH_DP")
			(clearance -0.0508)
			(thermal_gap 0.127)
			(padstack
				(mode front_inner_back)
				(layer "Inner"
					(shape circle)
					(size 1.1684 1.1684)
					(clearance 0.127)
				)
				(layer "B.Cu"
					(shape circle)
					(size 1.524 1.524)
					(clearance -0.0508)
				)
			)
		)
		(pad "2" thru_hole circle
			(at 1.27 -1.27 270)
			(size 1.524 1.524)
			(drill 0.9144)
			(layers "*.Cu" "*.Mask")
			(remove_unused_layers no)
			(net "L12_100OHM_6INCH_DN")
			(clearance -0.0508)
			(thermal_gap 0.127)
			(padstack
				(mode front_inner_back)
				(layer "Inner"
					(shape circle)
					(size 1.1684 1.1684)
					(clearance 0.127)
				)
				(layer "B.Cu"
					(shape circle)
					(size 1.524 1.524)
					(clearance -0.0508)
				)
			)
		)
		(pad "GND1" thru_hole rect
			(at -1.27 1.27 270)
			(size 1.524 1.524)
			(drill 0.9144)
			(layers "*.Cu" "*.Mask")
			(remove_unused_layers no)
			(net "GND")
			(clearance -0.0508)
			(thermal_gap 0.127)
			(padstack
				(mode front_inner_back)
				(layer "Inner"
					(shape circle)
					(size 1.1684 1.1684)
					(clearance 0.127)
				)
				(layer "B.Cu"
					(shape rect)
					(size 1.524 1.524)
					(clearance -0.0508)
				)
			)
		)
		(pad "GND2" thru_hole rect
			(at 1.27 1.27 270)
			(size 1.524 1.524)
			(drill 0.9144)
			(layers "*.Cu" "*.Mask")
			(remove_unused_layers no)
			(net "GND")
			(clearance -0.0508)
			(thermal_gap 0.127)
			(padstack
				(mode front_inner_back)
				(layer "Inner"
					(shape circle)
					(size 1.1684 1.1684)
					(clearance 0.127)
				)
				(layer "B.Cu"
					(shape rect)
					(size 1.524 1.524)
					(clearance -0.0508)
				)
			)
		)
	)
	(footprint ""
		(layer "F.Cu")
		(at 370.7384 -128.524 -90)
		(property "Reference" "R7B7"
			(at 0 0 270)
			(layer "F.SilkS")
			(hide yes)
			(effects
				(font
					(size 1.27 1.27)
				)
			)
		)
		(property "Value" ""
			(at 0 0 270)
			(layer "F.Fab")
			(effects
				(font
					(size 1.27 1.27)
				)
			)
		)
		(duplicate_pad_numbers_are_jumpers no)
		(fp_poly
			(pts
				(xy -0.2794 -0.1016) (xy 0.2794 -0.1016) (xy 0.2794 0.9906) (xy -0.2794 0.9906)
			)
			(stroke
				(width 0)
				(type default)
			)
			(fill no)
			(layer "F.CrtYd")
		)
		(fp_line
			(start -0.2794 0.9906)
			(end 0.2794 0.9906)
			(stroke
				(width 0.1)
				(type default)
			)
			(layer "F.Fab")
		)
		(fp_line
			(start 0.2794 0.9906)
			(end 0.2794 -0.1016)
			(stroke
				(width 0.1)
				(type default)
			)
			(layer "F.Fab")
		)
		(fp_line
			(start -0.2794 -0.1016)
			(end -0.2794 0.9906)
			(stroke
				(width 0.1)
				(type default)
			)
			(layer "F.Fab")
		)
		(fp_line
			(start 0.2794 -0.1016)
			(end -0.2794 -0.1016)
			(stroke
				(width 0.1)
				(type default)
			)
			(layer "F.Fab")
		)
		(pad "1" smd rect
			(at 0 0 270)
			(size 0.508 0.508)
			(layers "F.Cu" "F.Mask" "F.Paste")
			(net "A_EXTCLKP")
		)
		(pad "2" smd rect
			(at 0 0.889 270)
			(size 0.508 0.508)
			(layers "F.Cu" "F.Mask" "F.Paste")
			(net "GND")
		)
		(zone
			(layer "F.Cu")
			(hatch none 0.5)
			(connect_pads
				(clearance 0)
			)
			(min_thickness 0.25)
			(keepout
				(tracks not_allowed)
				(vias allowed)
				(pads allowed)
				(copperpour not_allowed)
				(footprints allowed)
			)
			(placement
				(enabled no)
				(sheetname "")
			)
			(fill
				(thermal_gap 0.5)
				(thermal_bridge_width 0.5)
				(island_removal_mode 0)
			)
			(polygon
				(pts
					(xy 370.1034 -128.778) (xy 370.1034 -128.27) (xy 370.4844 -128.27) (xy 370.4844 -128.778)
				)
			)
		)
		(zone
			(layer "F.Cu")
			(hatch none 0.5)
			(connect_pads
				(clearance 0)
			)
			(min_thickness 0.25)
			(keepout
				(tracks allowed)
				(vias not_allowed)
				(pads allowed)
				(copperpour not_allowed)
				(footprints allowed)
			)
			(placement
				(enabled no)
				(sheetname "")
			)
			(fill
				(thermal_gap 0.5)
				(thermal_bridge_width 0.5)
				(island_removal_mode 0)
			)
			(polygon
				(pts
					(xy 370.4844 -128.778) (xy 370.4844 -128.27) (xy 370.1034 -128.27) (xy 370.1034 -128.778)
				)
			)
		)
	)
	(footprint ""
		(layer "F.Cu")
		(at 195.58 -22.606 90)
		(property "Reference" "C4F10"
			(at 0 0 90)
			(layer "F.SilkS")
			(hide yes)
			(effects
				(font
					(size 1.27 1.27)
				)
			)
		)
		(property "Value" ""
			(at 0 0 90)
			(layer "F.Fab")
			(effects
				(font
					(size 1.27 1.27)
				)
			)
		)
		(duplicate_pad_numbers_are_jumpers no)
		(fp_poly
			(pts
				(xy 0.3048 -0.1016) (xy 0.3048 0.9906) (xy -0.3048 0.9906) (xy -0.3048 -0.1016)
			)
			(stroke
				(width 0)
				(type default)
			)
			(fill no)
			(layer "F.CrtYd")
		)
		(fp_line
			(start 0.3048 -0.1016)
			(end -0.3048 -0.1016)
			(stroke
				(width 0.1)
				(type default)
			)
			(layer "F.Fab")
		)
		(fp_line
			(start -0.3048 -0.1016)
			(end -0.3048 0.9906)
			(stroke
				(width 0.1)
				(type default)
			)
			(layer "F.Fab")
		)
		(fp_line
			(start 0.3048 0.9906)
			(end 0.3048 -0.1016)
			(stroke
				(width 0.1)
				(type default)
			)
			(layer "F.Fab")
		)
		(fp_line
			(start -0.3048 0.9906)
			(end 0.3048 0.9906)
			(stroke
				(width 0.1)
				(type default)
			)
			(layer "F.Fab")
		)
		(pad "1" smd rect
			(at 0 0 90)
			(size 0.508 0.508)
			(layers "F.Cu" "F.Mask" "F.Paste")
			(net "M_A_VREF")
		)
		(pad "2" smd rect
			(at 0 0.889 90)
			(size 0.508 0.508)
			(layers "F.Cu" "F.Mask" "F.Paste")
			(net "GND")
		)
		(zone
			(layer "F.Cu")
			(hatch none 0.5)
			(connect_pads
				(clearance 0)
			)
			(min_thickness 0.25)
			(keepout
				(tracks allowed)
				(vias not_allowed)
				(pads allowed)
				(copperpour not_allowed)
				(footprints allowed)
			)
			(placement
				(enabled no)
				(sheetname "")
			)
			(fill
				(thermal_gap 0.5)
				(thermal_bridge_width 0.5)
				(island_removal_mode 0)
			)
			(polygon
				(pts
					(xy 195.834 -22.352) (xy 195.834 -22.86) (xy 196.215 -22.86) (xy 196.215 -22.352)
				)
			)
		)
		(zone
			(layer "F.Cu")
			(hatch none 0.5)
			(connect_pads
				(clearance 0)
			)
			(min_thickness 0.25)
			(keepout
				(tracks not_allowed)
				(vias allowed)
				(pads allowed)
				(copperpour not_allowed)
				(footprints allowed)
			)
			(placement
				(enabled no)
				(sheetname "")
			)
			(fill
				(thermal_gap 0.5)
				(thermal_bridge_width 0.5)
				(island_removal_mode 0)
			)
			(polygon
				(pts
					(xy 196.215 -22.352) (xy 196.215 -22.86) (xy 195.834 -22.86) (xy 195.834 -22.352)
				)
			)
		)
	)
	(footprint ""
		(layer "F.Cu")
		(at 33.925002 -73.295764 90)
		(property "Reference" "EU1D3"
			(at 2.420366 5.267198 0)
			(unlocked yes)
			(layer "F.SilkS")
			(effects
				(font
					(size 0.7874 0.5842)
					(thickness 0.1524)
				)
			)
		)
		(property "Value" ""
			(at 0 0 90)
			(layer "F.Fab")
			(effects
				(font
					(size 1.27 1.27)
				)
			)
		)
		(duplicate_pad_numbers_are_jumpers no)
		(fp_line
			(start 2.9718 -3.5052)
			(end 2.9718 3.429)
			(stroke
				(width 0.1524)
				(type default)
			)
			(layer "F.SilkS")
		)
		(fp_line
			(start -3.0099 -3.5052)
			(end 2.9718 -3.5052)
			(stroke
				(width 0.1524)
				(type default)
			)
			(layer "F.SilkS")
		)
		(fp_line
			(start 2.9718 3.429)
			(end -3.0099 3.429)
			(stroke
				(width 0.1524)
				(type default)
			)
			(layer "F.SilkS")
		)
		(fp_line
			(start -3.0099 3.429)
			(end -3.0099 -3.5052)
			(stroke
				(width 0.1524)
				(type default)
			)
			(layer "F.SilkS")
		)
		(fp_circle
			(center -3.057398 -2.678684)
			(end -3.057398 -2.551684)
			(stroke
				(width 0.254)
				(type default)
			)
			(fill no)
			(layer "F.SilkS")
		)
		(fp_poly
			(pts
				(xy -2.9972 -3.4925) (xy -2.9972 -2.6924) (xy -2.1971 -3.4925)
			)
			(stroke
				(width 0)
				(type default)
			)
			(fill yes)
			(layer "F.SilkS")
		)
		(fp_poly
			(pts
				(xy -2.549906 -3.050032) (xy -2.549906 3.050032) (xy 2.549906 3.050032) (xy 2.549906 -3.050032)
			)
			(stroke
				(width 0)
				(type default)
			)
			(fill no)
			(layer "F.CrtYd")
		)
		(fp_line
			(start 2.549906 -3.050032)
			(end 2.549906 3.050032)
			(stroke
				(width 0.1)
				(type default)
			)
			(layer "F.Fab")
		)
		(fp_line
			(start -2.549906 -3.050032)
			(end 2.549906 -3.050032)
			(stroke
				(width 0.1)
				(type default)
			)
			(layer "F.Fab")
		)
		(fp_line
			(start 2.549906 3.050032)
			(end -2.549906 3.050032)
			(stroke
				(width 0.1)
				(type default)
			)
			(layer "F.Fab")
		)
		(fp_line
			(start -2.549906 3.050032)
			(end -2.549906 -3.050032)
			(stroke
				(width 0.1)
				(type default)
			)
			(layer "F.Fab")
		)
		(fp_circle
			(center -3.057398 -2.678684)
			(end -3.057398 -2.551684)
			(stroke
				(width 0.254)
				(type default)
			)
			(fill no)
			(layer "F.Fab")
		)
		(pad "1" smd rect
			(at -2.39522 -2.279904 90)
			(size 0.7112 0.254)
			(layers "F.Cu" "F.Mask" "F.Paste")
			(net "PVCCIN_CPU1")
		)
		(pad "2" smd rect
			(at -2.39522 -1.83007 90)
			(size 0.7112 0.254)
			(layers "F.Cu" "F.Mask" "F.Paste")
			(net "GND")
		)
		(pad "3" smd rect
			(at -2.39522 -1.379982 90)
			(size 0.7112 0.254)
			(layers "F.Cu" "F.Mask" "F.Paste")
			(net "VR_PVCCIN_CPU1_PH3_VCIN")
		)
		(pad "4" smd rect
			(at -2.39522 -0.929894 90)
			(size 0.7112 0.254)
			(layers "F.Cu" "F.Mask" "F.Paste")
			(net "P5V_STBY")
		)
		(pad "5" smd rect
			(at -2.39522 -0.48006 90)
			(size 0.7112 0.254)
			(layers "F.Cu" "F.Mask" "F.Paste")
			(net "GND")
		)
		(pad "6" smd rect
			(at -2.39522 -0.029972 90)
			(size 0.7112 0.254)
			(layers "F.Cu" "F.Mask" "F.Paste")
			(net "TP_PVCCIN_CPU1_PH3_GL_0")
		)
		(pad "7" smd custom
			(at 0.016764 1.145032 90)
			(size 0.53975 0.53975)
			(layers "F.Cu" "F.Mask" "F.Paste")
			(net "GND")
			(options
				(clearance outline)
				(anchor circle)
			)
			(primitives
				(gr_poly
					(pts
						(xy -2.7051 1.0795) (xy -2.7051 -0.3683) (xy -0.9271 -0.3683) (xy -0.9271 -1.0795) (xy 2.7051 -1.0795)
						(xy 2.7051 1.0795)
					)
					(width 0)
					(fill yes)
				)
			)
		)
		(pad "10" smd rect
			(at -0.008382 2.874772 90)
			(size 4.3434 0.6096)
			(layers "F.Cu" "F.Mask" "F.Paste")
			(net "VR_PVCCIN_CPU1_PHASE3")
		)
		(pad "25" smd rect
			(at 1.548384 -1.283208 90)
			(size 2.3368 2.0066)
			(layers "F.Cu" "F.Mask" "F.Paste")
			(net "VR_FET_SW_P12V_STBY_PVCCIN_CPU1")
		)
		(pad "30" smd rect
			(at 2.050034 -2.895092 90)
			(size 0.254 0.7112)
			(layers "F.Cu" "F.Mask" "F.Paste")
			(net "VR_FET_SW_P12V_STBY_PVCCIN_CPU1")
		)
		(pad "31" smd rect
			(at 1.599946 -2.895092 90)
			(size 0.254 0.7112)
			(layers "F.Cu" "F.Mask" "F.Paste")
			(net "Net_294")
		)
		(pad "32" smd rect
			(at 1.150112 -2.895092 90)
			(size 0.254 0.7112)
			(layers "F.Cu" "F.Mask" "F.Paste")
			(net "VR_PVCCIN_CPU1_PH3_PHASE")
		)
		(pad "33" smd rect
			(at 0.700024 -2.895092 90)
			(size 0.254 0.7112)
			(layers "F.Cu" "F.Mask" "F.Paste")
			(net "VR_PVCCIN_CPU1_PH3_BOOT_R")
		)
		(pad "34" smd rect
			(at 0.249936 -2.895092 90)
			(size 0.254 0.7112)
			(layers "F.Cu" "F.Mask" "F.Paste")
			(net "VR_PVCCIN_CPU1_PWM3")
		)
		(pad "35" smd rect
			(at -0.199898 -2.895092 90)
			(size 0.254 0.7112)
			(layers "F.Cu" "F.Mask" "F.Paste")
			(net "P5V_STBY")
		)
		(pad "36" smd rect
			(at -0.649986 -2.895092 90)
			(size 0.254 0.7112)
			(layers "F.Cu" "F.Mask" "F.Paste")
			(net "A_TSENSE_PVCCIN_CPU1")
		)
		(pad "37" smd rect
			(at -1.100074 -2.895092 90)
			(size 0.254 0.7112)
			(layers "F.Cu" "F.Mask" "F.Paste")
			(net "VR_PVCCIN_CPU1_PH3_OCSET")
		)
		(pad "38" smd rect
			(at -1.549908 -2.895092 90)
			(size 0.254 0.7112)
			(layers "F.Cu" "F.Mask" "F.Paste")
			(net "ISENSE_PVCCIN_CPU1_PH3_IMON")
		)
		(pad "39" smd rect
			(at -1.999996 -2.895092 90)
			(size 0.254 0.7112)
			(layers "F.Cu" "F.Mask" "F.Paste")
			(net "VR_PVCCIN_CPU1_AIREF3")
		)
		(pad "40" smd rect
			(at -0.871728 -1.283208 90)
			(size 1.8034 2.0066)
			(layers "F.Cu" "F.Mask" "F.Paste")
			(net "GND")
		)
		(pad "41" smd rect
			(at -1.533906 0.247904 90)
			(size 0.508 0.3556)
			(layers "F.Cu" "F.Mask" "F.Paste")
			(net "TP_PVCCIN_CPU1_PH3_GL_1")
		)
	)
)
